# T6G (Grand Teton) — schematic netlist excerpt (pin names and nets, part order shuffled) for the footprints in the layout excerpt that follows; sources: Cadence DE-HDL packaged netlist, KiCad conversion of 04192023_DAF0TMB3IC0_F0TG_MB_C_brd_V02_OCP.brd

TP18  TP  NA  pkg TP  page 54 : TP = VSENSE_PVDD11_S3_P1_DP
PC6565  Q_CAP  100NF 50V 10% X7R  pkg C0402  page 363 : A = P0V9_CPU0_RT_2D ; B = GND
R1509  Q_RES  0 5% CHIP  pkg 0402LF  page 136 : A = HP_LVC3_OCP_V3_1_P12V_PWRGD ; B = HP_LVC3_OCP_V3_1_P12V_R2_PWRGD
C6530  Q_CAP_DIFFBUS  DIFF BUS_0.22UF 6.3V 20% X6S  pkg C0201  page 275 : \1\ = P5E_CPU0_P0_TX_BUF_C_DN<14> ; \2\ = P5E_CPU0_P0_TX_BUF_DN<14>

(kicad_pcb
	(version 20260206)
	(generator "pcbnew")
	(generator_version "10.0")
	(general
		(thickness 1.6)
		(legacy_teardrops no)
	)
	(paper "A4")
	(title_block
		(title "04192023_DAF0TMB3IC0_F0TG_MB_C_brd_V02_OCP.brd")
		(comment 1 "Grand Teton / footprints 2196-2199 of 8354")
	)
	(layers
		(0 "F.Cu" signal "TOP")
		(4 "In1.Cu" signal "GND")
		(6 "In2.Cu" signal "IN1")
		(8 "In3.Cu" signal "GND1")
		(10 "In4.Cu" signal "IN2")
		(12 "In5.Cu" signal "GND2")
		(14 "In6.Cu" signal "IN3")
		(16 "In7.Cu" signal "GND3")
		(18 "In8.Cu" signal "VCC")
		(20 "In9.Cu" signal "VCC1")
		(22 "In10.Cu" signal "GND4")
		(24 "In11.Cu" signal "IN4")
		(26 "In12.Cu" signal "GND5")
		(28 "In13.Cu" signal "IN5")
		(30 "In14.Cu" signal "GND6")
		(32 "In15.Cu" signal "IN6")
		(34 "In16.Cu" signal "GND7")
		(2 "B.Cu" signal "BOTTOM")
		(9 "F.Adhes" user "F.Adhesive")
		(11 "B.Adhes" user "B.Adhesive")
		(13 "F.Paste" user "Package Geometry/Pastemask Top")
		(15 "B.Paste" user "Package Geometry/Pastemask Bottom")
		(5 "F.SilkS" user "Ref Des/Silkscreen Top")
		(7 "B.SilkS" user "Ref Des/Silkscreen Bottom")
		(1 "F.Mask" user "Board Geometry/Soldermask Top")
		(3 "B.Mask" user "Board Geometry/Soldermask Bottom")
		(17 "Dwgs.User" user "User.Drawings")
		(19 "Cmts.User" user "User.Comments")
		(21 "Eco1.User" user "User.Eco1")
		(23 "Eco2.User" user "User.Eco2")
		(25 "Edge.Cuts" user "Board Geometry/Outline")
		(27 "Margin" user)
		(31 "F.CrtYd" user "Package Geometry/Place Bound Top")
		(29 "B.CrtYd" user "Package Geometry/Place Bound Bottom")
		(35 "F.Fab" user "Ref Des/Assembly Top")
		(33 "B.Fab" user "Ref Des/Assembly Bottom")
	)
	(footprint ""
		(layer "F.Cu")
		(at 442.134752 -389.281416 90)
		(property "Reference" "PC6565"
			(at 0 0 90)
			(layer "F.SilkS")
			(hide yes)
			(effects
				(font
					(size 1.27 1.27)
				)
			)
		)
		(property "Value" ""
			(at 0 0 90)
			(layer "F.Fab")
			(effects
				(font
					(size 1.27 1.27)
				)
			)
		)
		(duplicate_pad_numbers_are_jumpers no)
		(fp_line
			(start 0.7874 -0.4064)
			(end 0.7874 0.4064)
			(stroke
				(width 0.1524)
				(type default)
			)
			(layer "F.SilkS")
		)
		(fp_line
			(start -0.7874 -0.4064)
			(end 0.7874 -0.4064)
			(stroke
				(width 0.1524)
				(type default)
			)
			(layer "F.SilkS")
		)
		(fp_line
			(start 0.7874 0.4064)
			(end -0.7874 0.4064)
			(stroke
				(width 0.1524)
				(type default)
			)
			(layer "F.SilkS")
		)
		(fp_line
			(start -0.7874 0.4064)
			(end -0.7874 -0.4064)
			(stroke
				(width 0.1524)
				(type default)
			)
			(layer "F.SilkS")
		)
		(fp_line
			(start -0.12065 -0.305054)
			(end -0.12065 -0.2794)
			(stroke
				(width 0.1)
				(type default)
			)
			(layer "F.Fab")
		)
		(fp_line
			(start -0.67945 -0.305054)
			(end -0.12065 -0.305054)
			(stroke
				(width 0.1)
				(type default)
			)
			(layer "F.Fab")
		)
		(fp_line
			(start 0.67945 -0.3048)
			(end 0.67945 0.3048)
			(stroke
				(width 0.1)
				(type default)
			)
			(layer "F.Fab")
		)
		(fp_line
			(start 0.12065 -0.3048)
			(end 0.67945 -0.3048)
			(stroke
				(width 0.1)
				(type default)
			)
			(layer "F.Fab")
		)
		(fp_line
			(start 0.12065 -0.2794)
			(end 0.12065 -0.3048)
			(stroke
				(width 0.1)
				(type default)
			)
			(layer "F.Fab")
		)
		(fp_line
			(start -0.12065 -0.2794)
			(end 0.12065 -0.2794)
			(stroke
				(width 0.1)
				(type default)
			)
			(layer "F.Fab")
		)
		(fp_line
			(start 0.120396 0.2794)
			(end -0.12065 0.2794)
			(stroke
				(width 0.1)
				(type default)
			)
			(layer "F.Fab")
		)
		(fp_line
			(start -0.12065 0.2794)
			(end -0.12065 0.3048)
			(stroke
				(width 0.1)
				(type default)
			)
			(layer "F.Fab")
		)
		(fp_line
			(start 0.67945 0.3048)
			(end 0.120396 0.3048)
			(stroke
				(width 0.1)
				(type default)
			)
			(layer "F.Fab")
		)
		(fp_line
			(start 0.120396 0.3048)
			(end 0.120396 0.2794)
			(stroke
				(width 0.1)
				(type default)
			)
			(layer "F.Fab")
		)
		(fp_line
			(start -0.12065 0.3048)
			(end -0.67945 0.3048)
			(stroke
				(width 0.1)
				(type default)
			)
			(layer "F.Fab")
		)
		(fp_line
			(start -0.67945 0.3048)
			(end -0.67945 -0.305054)
			(stroke
				(width 0.1)
				(type default)
			)
			(layer "F.Fab")
		)
		(pad "1" smd circle
			(at -0.40005 0 90)
			(size 0 0)
			(layers "F.Cu" "F.Mask" "F.Paste")
			(net "P0V9_CPU0_RT_2D")
		)
		(pad "2" smd circle
			(at 0.40005 0 90)
			(size 0 0)
			(layers "F.Cu" "F.Mask" "F.Paste")
			(net "GND")
		)
	)
	(footprint ""
		(layer "F.Cu")
		(at 221.28226 -98.11004 90)
		(property "Reference" "R1509"
			(at 0 0 90)
			(layer "F.SilkS")
			(hide yes)
			(effects
				(font
					(size 1.27 1.27)
				)
			)
		)
		(property "Value" ""
			(at 0 0 90)
			(layer "F.Fab")
			(effects
				(font
					(size 1.27 1.27)
				)
			)
		)
		(duplicate_pad_numbers_are_jumpers no)
		(fp_line
			(start 0.7874 -0.4064)
			(end 0.7874 0.4064)
			(stroke
				(width 0.1524)
				(type default)
			)
			(layer "F.SilkS")
		)
		(fp_line
			(start -0.7874 -0.4064)
			(end 0.7874 -0.4064)
			(stroke
				(width 0.1524)
				(type default)
			)
			(layer "F.SilkS")
		)
		(fp_line
			(start 0.7874 0.4064)
			(end -0.7874 0.4064)
			(stroke
				(width 0.1524)
				(type default)
			)
			(layer "F.SilkS")
		)
		(fp_line
			(start -0.7874 0.4064)
			(end -0.7874 -0.4064)
			(stroke
				(width 0.1524)
				(type default)
			)
			(layer "F.SilkS")
		)
		(fp_line
			(start -0.12065 -0.305054)
			(end -0.12065 -0.2794)
			(stroke
				(width 0.1)
				(type default)
			)
			(layer "F.Fab")
		)
		(fp_line
			(start -0.67945 -0.305054)
			(end -0.12065 -0.305054)
			(stroke
				(width 0.1)
				(type default)
			)
			(layer "F.Fab")
		)
		(fp_line
			(start 0.67945 -0.3048)
			(end 0.67945 0.3048)
			(stroke
				(width 0.1)
				(type default)
			)
			(layer "F.Fab")
		)
		(fp_line
			(start 0.12065 -0.3048)
			(end 0.67945 -0.3048)
			(stroke
				(width 0.1)
				(type default)
			)
			(layer "F.Fab")
		)
		(fp_line
			(start 0.12065 -0.2794)
			(end 0.12065 -0.3048)
			(stroke
				(width 0.1)
				(type default)
			)
			(layer "F.Fab")
		)
		(fp_line
			(start -0.12065 -0.2794)
			(end 0.12065 -0.2794)
			(stroke
				(width 0.1)
				(type default)
			)
			(layer "F.Fab")
		)
		(fp_line
			(start 0.120396 0.2794)
			(end -0.12065 0.2794)
			(stroke
				(width 0.1)
				(type default)
			)
			(layer "F.Fab")
		)
		(fp_line
			(start -0.12065 0.2794)
			(end -0.12065 0.3048)
			(stroke
				(width 0.1)
				(type default)
			)
			(layer "F.Fab")
		)
		(fp_line
			(start 0.67945 0.3048)
			(end 0.120396 0.3048)
			(stroke
				(width 0.1)
				(type default)
			)
			(layer "F.Fab")
		)
		(fp_line
			(start 0.120396 0.3048)
			(end 0.120396 0.2794)
			(stroke
				(width 0.1)
				(type default)
			)
			(layer "F.Fab")
		)
		(fp_line
			(start -0.12065 0.3048)
			(end -0.67945 0.3048)
			(stroke
				(width 0.1)
				(type default)
			)
			(layer "F.Fab")
		)
		(fp_line
			(start -0.67945 0.3048)
			(end -0.67945 -0.305054)
			(stroke
				(width 0.1)
				(type default)
			)
			(layer "F.Fab")
		)
		(pad "1" smd circle
			(at -0.40005 0 90)
			(size 0 0)
			(layers "F.Cu" "F.Mask" "F.Paste")
			(net "HP_LVC3_OCP_V3_1_P12V_PWRGD")
		)
		(pad "2" smd circle
			(at 0.40005 0 90)
			(size 0 0)
			(layers "F.Cu" "F.Mask" "F.Paste")
			(net "HP_LVC3_OCP_V3_1_P12V_R2_PWRGD")
		)
	)
	(footprint ""
		(layer "F.Cu")
		(at 346.653866 -416.899344 -90)
		(property "Reference" "C6530"
			(at 0 0 270)
			(layer "F.SilkS")
			(hide yes)
			(effects
				(font
					(size 1.27 1.27)
				)
			)
		)
		(property "Value" ""
			(at 0 0 270)
			(layer "F.Fab")
			(effects
				(font
					(size 1.27 1.27)
				)
			)
		)
		(duplicate_pad_numbers_are_jumpers no)
		(fp_line
			(start -0.299974 0.150114)
			(end -0.299974 -0.150114)
			(stroke
				(width 0.1)
				(type default)
			)
			(layer "F.Fab")
		)
		(fp_line
			(start 0.299974 0.150114)
			(end -0.299974 0.150114)
			(stroke
				(width 0.1)
				(type default)
			)
			(layer "F.Fab")
		)
		(fp_line
			(start -0.299974 -0.150114)
			(end 0.299974 -0.150114)
			(stroke
				(width 0.1)
				(type default)
			)
			(layer "F.Fab")
		)
		(fp_line
			(start 0.299974 -0.150114)
			(end 0.299974 0.150114)
			(stroke
				(width 0.1)
				(type default)
			)
			(layer "F.Fab")
		)
		(pad "1" smd rect
			(at -0.2667 0 270)
			(size 0.3048 0.381)
			(layers "F.Cu" "F.Mask" "F.Paste")
			(net "P5E_CPU0_P0_TX_BUF_C_DN<14>")
		)
		(pad "2" smd rect
			(at 0.2667 0 270)
			(size 0.3048 0.381)
			(layers "F.Cu" "F.Mask" "F.Paste")
			(net "P5E_CPU0_P0_TX_BUF_DN<14>")
		)
	)
	(footprint ""
		(layer "F.Cu")
		(at 169.1894 -333.375508)
		(property "Reference" "TP18"
			(at -2.305812 -5.26923 0)
			(unlocked yes)
			(layer "F.SilkS")
			(effects
				(font
					(size 0.7874 0.5842)
					(thickness 0.1524)
				)
				(justify left)
			)
		)
		(property "Value" ""
			(at 0 0 0)
			(layer "F.Fab")
			(effects
				(font
					(size 1.27 1.27)
				)
			)
		)
		(duplicate_pad_numbers_are_jumpers no)
		(pad "1" smd circle
			(at 0 0)
			(size 0.762 0.762)
			(layers "F.Cu" "F.Mask" "F.Paste")
			(net "VSENSE_PVDD11_S3_P1_DP")
		)
	)
)
